0.00800 T01
0.01000 T02
0.01200 T03
0.01400 T04
0.01417 T05
0.01600 T06
0.02800 T07
0.03200 T08
0.03400 T09
0.03500 T010
0.04000 T011
0.04400 T012
0.04800 T013
0.06300 T014
0.08600 T015
0.09400 T016
0.09700 T017
0.12600 T018
0.13000 T019
0.13400 T020
0.13800 T021
0.15800 T022
0.16800 T023
